# S9S_MB_2U (Grand Teton) — schematic netlist excerpt (pin names and nets, part order shuffled) for the footprints in the layout excerpt that follows; sources: Cadence DE-HDL packaged netlist, KiCad conversion of 03242023_DA0F0TMBIJ0_F0T_Motherboard_J_brd_V01_OCP.brd

PC1675  Q_CAP  22UF 16V 20% X6S  pkg C0805  page 272 : A = SW_P12V_PVCCFA_EHV_FIVRA_CPU0_R ; B = GND
R4296  Q_RES  100 1% CHIP  pkg 0402LF  page 124 : A = PWRGD_DRAMPWRGD_CPU0_CD_LVC1_R2 ; B = PWRGD_DRAMPWRGD_CPU0_CD_LVC1_R
R155  Q_RES  100 1% CHIP  pkg 0402LF  page 125 : A = PWRGD_CPU1_BUF_R ; B = PVNN_TERM_CPU1

(kicad_pcb
	(version 20260206)
	(generator "pcbnew")
	(generator_version "10.0")
	(general
		(thickness 1.6)
		(legacy_teardrops no)
	)
	(paper "A4")
	(title_block
		(title "03242023_DA0F0TMBIJ0_F0T_Motherboard_J_brd_V01_OCP.brd")
		(comment 1 "Grand Teton / footprints 5670-5672 of 6105")
	)
	(layers
		(0 "F.Cu" signal "TOP")
		(4 "In1.Cu" signal "GND")
		(6 "In2.Cu" signal "IN1")
		(8 "In3.Cu" signal "GND1")
		(10 "In4.Cu" signal "IN2")
		(12 "In5.Cu" signal "GND2")
		(14 "In6.Cu" signal "IN3")
		(16 "In7.Cu" signal "GND3")
		(18 "In8.Cu" signal "VCC")
		(20 "In9.Cu" signal "VCC1")
		(22 "In10.Cu" signal "GND4")
		(24 "In11.Cu" signal "IN4")
		(26 "In12.Cu" signal "GND5")
		(28 "In13.Cu" signal "IN5")
		(30 "In14.Cu" signal "GND6")
		(32 "In15.Cu" signal "IN6")
		(34 "In16.Cu" signal "GND7")
		(2 "B.Cu" signal "BOTTOM")
		(9 "F.Adhes" user "F.Adhesive")
		(11 "B.Adhes" user "B.Adhesive")
		(13 "F.Paste" user "Package Geometry/Pastemask Top")
		(15 "B.Paste" user "Package Geometry/Pastemask Bottom")
		(5 "F.SilkS" user "Ref Des/Silkscreen Top")
		(7 "B.SilkS" user "Ref Des/Silkscreen Bottom")
		(1 "F.Mask" user "Board Geometry/Soldermask Top")
		(3 "B.Mask" user "Board Geometry/Soldermask Bottom")
		(17 "Dwgs.User" user "User.Drawings")
		(19 "Cmts.User" user "User.Comments")
		(21 "Eco1.User" user "User.Eco1")
		(23 "Eco2.User" user "User.Eco2")
		(25 "Edge.Cuts" user "Board Geometry/Outline")
		(27 "Margin" user)
		(31 "F.CrtYd" user "Package Geometry/Place Bound Top")
		(29 "B.CrtYd" user "Package Geometry/Place Bound Bottom")
		(35 "F.Fab" user "Ref Des/Assembly Top")
		(33 "B.Fab" user "Ref Des/Assembly Bottom")
	)
	(footprint ""
		(layer "B.Cu")
		(at 420.453312 -366.454944 180)
		(property "Reference" "PC1675"
			(at 0 0 0)
			(layer "B.SilkS")
			(hide yes)
			(effects
				(font
					(size 1.27 1.27)
				)
				(justify mirror)
			)
		)
		(property "Value" ""
			(at 0 0 0)
			(layer "B.Fab")
			(effects
				(font
					(size 1.27 1.27)
				)
				(justify mirror)
			)
		)
		(duplicate_pad_numbers_are_jumpers no)
		(fp_line
			(start 1.524 0.762)
			(end 1.524 -0.762)
			(stroke
				(width 0.1524)
				(type default)
			)
			(layer "B.SilkS")
		)
		(fp_line
			(start 1.524 -0.762)
			(end -1.524 -0.762)
			(stroke
				(width 0.1524)
				(type default)
			)
			(layer "B.SilkS")
		)
		(fp_line
			(start -1.524 0.762)
			(end 1.524 0.762)
			(stroke
				(width 0.1524)
				(type default)
			)
			(layer "B.SilkS")
		)
		(fp_line
			(start -1.524 -0.762)
			(end -1.524 0.762)
			(stroke
				(width 0.1524)
				(type default)
			)
			(layer "B.SilkS")
		)
		(fp_line
			(start 1.1049 0.724916)
			(end -1.1049 0.724916)
			(stroke
				(width 0.1)
				(type default)
			)
			(layer "B.Fab")
		)
		(fp_line
			(start 1.1049 -0.724916)
			(end 1.1049 0.724916)
			(stroke
				(width 0.1)
				(type default)
			)
			(layer "B.Fab")
		)
		(fp_line
			(start -1.1049 0.724916)
			(end -1.1049 -0.724916)
			(stroke
				(width 0.1)
				(type default)
			)
			(layer "B.Fab")
		)
		(fp_line
			(start -1.1049 -0.724916)
			(end 1.1049 -0.724916)
			(stroke
				(width 0.1)
				(type default)
			)
			(layer "B.Fab")
		)
		(pad "1" smd rect
			(at 0.889 0 180)
			(size 1.016 1.27)
			(layers "B.Cu" "B.Mask" "B.Paste")
			(net "SW_P12V_PVCCFA_EHV_FIVRA_CPU0_R")
		)
		(pad "2" smd rect
			(at -0.889 0 180)
			(size 1.016 1.27)
			(layers "B.Cu" "B.Mask" "B.Paste")
			(net "GND")
		)
	)
	(footprint ""
		(layer "B.Cu")
		(at 299.679868 -198.197978 -90)
		(property "Reference" "R4296"
			(at 0 0 90)
			(layer "B.SilkS")
			(hide yes)
			(effects
				(font
					(size 1.27 1.27)
				)
				(justify mirror)
			)
		)
		(property "Value" ""
			(at 0 0 90)
			(layer "B.Fab")
			(effects
				(font
					(size 1.27 1.27)
				)
				(justify mirror)
			)
		)
		(duplicate_pad_numbers_are_jumpers no)
		(fp_line
			(start -0.7874 0.4064)
			(end 0.7874 0.4064)
			(stroke
				(width 0.1524)
				(type default)
			)
			(layer "B.SilkS")
		)
		(fp_line
			(start 0.7874 0.4064)
			(end 0.7874 -0.4064)
			(stroke
				(width 0.1524)
				(type default)
			)
			(layer "B.SilkS")
		)
		(fp_line
			(start -0.7874 -0.4064)
			(end -0.7874 0.4064)
			(stroke
				(width 0.1524)
				(type default)
			)
			(layer "B.SilkS")
		)
		(fp_line
			(start 0.7874 -0.4064)
			(end -0.7874 -0.4064)
			(stroke
				(width 0.1524)
				(type default)
			)
			(layer "B.SilkS")
		)
		(fp_line
			(start -0.67945 0.3048)
			(end -0.120396 0.3048)
			(stroke
				(width 0.1)
				(type default)
			)
			(layer "B.Fab")
		)
		(fp_line
			(start -0.120396 0.3048)
			(end -0.120396 0.2794)
			(stroke
				(width 0.1)
				(type default)
			)
			(layer "B.Fab")
		)
		(fp_line
			(start 0.12065 0.3048)
			(end 0.67945 0.3048)
			(stroke
				(width 0.1)
				(type default)
			)
			(layer "B.Fab")
		)
		(fp_line
			(start 0.67945 0.3048)
			(end 0.67945 -0.305054)
			(stroke
				(width 0.1)
				(type default)
			)
			(layer "B.Fab")
		)
		(fp_line
			(start -0.120396 0.2794)
			(end 0.12065 0.2794)
			(stroke
				(width 0.1)
				(type default)
			)
			(layer "B.Fab")
		)
		(fp_line
			(start 0.12065 0.2794)
			(end 0.12065 0.3048)
			(stroke
				(width 0.1)
				(type default)
			)
			(layer "B.Fab")
		)
		(fp_line
			(start -0.12065 -0.2794)
			(end -0.12065 -0.3048)
			(stroke
				(width 0.1)
				(type default)
			)
			(layer "B.Fab")
		)
		(fp_line
			(start 0.12065 -0.2794)
			(end -0.12065 -0.2794)
			(stroke
				(width 0.1)
				(type default)
			)
			(layer "B.Fab")
		)
		(fp_line
			(start -0.67945 -0.3048)
			(end -0.67945 0.3048)
			(stroke
				(width 0.1)
				(type default)
			)
			(layer "B.Fab")
		)
		(fp_line
			(start -0.12065 -0.3048)
			(end -0.67945 -0.3048)
			(stroke
				(width 0.1)
				(type default)
			)
			(layer "B.Fab")
		)
		(fp_line
			(start 0.12065 -0.305054)
			(end 0.12065 -0.2794)
			(stroke
				(width 0.1)
				(type default)
			)
			(layer "B.Fab")
		)
		(fp_line
			(start 0.67945 -0.305054)
			(end 0.12065 -0.305054)
			(stroke
				(width 0.1)
				(type default)
			)
			(layer "B.Fab")
		)
		(pad "1" smd circle
			(at 0.40005 0 90)
			(size 0 0)
			(layers "B.Cu" "B.Mask" "B.Paste")
			(net "PWRGD_DRAMPWRGD_CPU0_CD_LVC1_R2")
		)
		(pad "2" smd circle
			(at -0.40005 0 90)
			(size 0 0)
			(layers "B.Cu" "B.Mask" "B.Paste")
			(net "PWRGD_DRAMPWRGD_CPU0_CD_LVC1_R")
		)
	)
	(footprint ""
		(layer "B.Cu")
		(at 67.320922 -183.303926 -90)
		(property "Reference" "R155"
			(at 0 0 90)
			(layer "B.SilkS")
			(hide yes)
			(effects
				(font
					(size 1.27 1.27)
				)
				(justify mirror)
			)
		)
		(property "Value" ""
			(at 0 0 90)
			(layer "B.Fab")
			(effects
				(font
					(size 1.27 1.27)
				)
				(justify mirror)
			)
		)
		(duplicate_pad_numbers_are_jumpers no)
		(fp_line
			(start -0.7874 0.4064)
			(end 0.7874 0.4064)
			(stroke
				(width 0.1524)
				(type default)
			)
			(layer "B.SilkS")
		)
		(fp_line
			(start 0.7874 0.4064)
			(end 0.7874 -0.4064)
			(stroke
				(width 0.1524)
				(type default)
			)
			(layer "B.SilkS")
		)
		(fp_line
			(start -0.7874 -0.4064)
			(end -0.7874 0.4064)
			(stroke
				(width 0.1524)
				(type default)
			)
			(layer "B.SilkS")
		)
		(fp_line
			(start 0.7874 -0.4064)
			(end -0.7874 -0.4064)
			(stroke
				(width 0.1524)
				(type default)
			)
			(layer "B.SilkS")
		)
		(fp_line
			(start -0.67945 0.3048)
			(end -0.120396 0.3048)
			(stroke
				(width 0.1)
				(type default)
			)
			(layer "B.Fab")
		)
		(fp_line
			(start -0.120396 0.3048)
			(end -0.120396 0.2794)
			(stroke
				(width 0.1)
				(type default)
			)
			(layer "B.Fab")
		)
		(fp_line
			(start 0.12065 0.3048)
			(end 0.67945 0.3048)
			(stroke
				(width 0.1)
				(type default)
			)
			(layer "B.Fab")
		)
		(fp_line
			(start 0.67945 0.3048)
			(end 0.67945 -0.305054)
			(stroke
				(width 0.1)
				(type default)
			)
			(layer "B.Fab")
		)
		(fp_line
			(start -0.120396 0.2794)
			(end 0.12065 0.2794)
			(stroke
				(width 0.1)
				(type default)
			)
			(layer "B.Fab")
		)
		(fp_line
			(start 0.12065 0.2794)
			(end 0.12065 0.3048)
			(stroke
				(width 0.1)
				(type default)
			)
			(layer "B.Fab")
		)
		(fp_line
			(start -0.12065 -0.2794)
			(end -0.12065 -0.3048)
			(stroke
				(width 0.1)
				(type default)
			)
			(layer "B.Fab")
		)
		(fp_line
			(start 0.12065 -0.2794)
			(end -0.12065 -0.2794)
			(stroke
				(width 0.1)
				(type default)
			)
			(layer "B.Fab")
		)
		(fp_line
			(start -0.67945 -0.3048)
			(end -0.67945 0.3048)
			(stroke
				(width 0.1)
				(type default)
			)
			(layer "B.Fab")
		)
		(fp_line
			(start -0.12065 -0.3048)
			(end -0.67945 -0.3048)
			(stroke
				(width 0.1)
				(type default)
			)
			(layer "B.Fab")
		)
		(fp_line
			(start 0.12065 -0.305054)
			(end 0.12065 -0.2794)
			(stroke
				(width 0.1)
				(type default)
			)
			(layer "B.Fab")
		)
		(fp_line
			(start 0.67945 -0.305054)
			(end 0.12065 -0.305054)
			(stroke
				(width 0.1)
				(type default)
			)
			(layer "B.Fab")
		)
		(pad "1" smd circle
			(at 0.40005 0 90)
			(size 0 0)
			(layers "B.Cu" "B.Mask" "B.Paste")
			(net "PWRGD_CPU1_BUF_R")
		)
		(pad "2" smd circle
			(at -0.40005 0 90)
			(size 0 0)
			(layers "B.Cu" "B.Mask" "B.Paste")
			(net "PVNN_TERM_CPU1")
		)
	)
)
